FILE_TYPE = MACRO_DRAWING;
SET COLOR_WIRE YELLOW;
SET COLOR_PROP ORANGE;
SET COLOR_DOT WHITE;
SET COLOR_ARC YELLOW;
SET COLOR_BODY GREEN;
SET COLOR_NOTE PURPLE;
SET PROP_DISPLAY VALUE;
SET PAGE_NUMBER P420;
FORCEADD VCC_CORE..1
(-4700 4850);
FORCEPROP 3 LASTPIN (-4700 4800) SIG_NAME P0V9_CPU0_RT2_2A\g
J 0
(-4690 4810);
DISPLAY 0.659574 (-4690 4810);
PAINT MONO (-4690 4810);
DISPLAY INVISIBLE (-4690 4810);
FORCEPROP 1 LAST HDL_POWER P0V9_CPU0_RT2_2A
J 1
(-4700 4900);
DISPLAY 0.617021 (-4700 4900);
PAINT SKYBLUE (-4700 4900);
FORCEPROP 2 LAST CDS_LIB pure_quanta_power
J 0
(-4700 4850);
DISPLAY INVISIBLE (-4700 4850);
FORCEPROP 1 LAST PATH I10
J 0
(-4650 4875);
DISPLAY 0.872340 (-4650 4875);
PAINT AQUA (-4650 4875);
DISPLAY INVISIBLE (-4650 4875);
FORCEADD UNIVERSAL_GND..1
(-3150 1150);
FORCEPROP 3 LASTPIN (-3150 1200) SIG_NAME GND\g
J 0
(-3140 1210);
DISPLAY 0.659574 (-3140 1210);
PAINT MONO (-3140 1210);
DISPLAY INVISIBLE (-3140 1210);
FORCEPROP 2 LAST CDS_LIB pure_quanta_power
J 0
(-3150 1150);
DISPLAY INVISIBLE (-3150 1150);
FORCEPROP 1 LAST HDL_POWER GND
J 1
(-3125 1075);
DISPLAY 0.872340 (-3125 1075);
PAINT GREEN (-3125 1075);
DISPLAY INVISIBLE (-3125 1075);
FORCEPROP 1 LAST PATH I11
J 0
(-3075 1150);
DISPLAY 0.872340 (-3075 1150);
PAINT AQUA (-3075 1150);
DISPLAY INVISIBLE (-3075 1150);
FORCEADD UNIVERSAL_GND..1
(-1475 775);
FORCEPROP 3 LASTPIN (-1475 825) SIG_NAME GND\g
J 0
(-1465 835);
DISPLAY 0.659574 (-1465 835);
PAINT MONO (-1465 835);
DISPLAY INVISIBLE (-1465 835);
FORCEPROP 2 LAST CDS_LIB pure_quanta_power
J 0
(-1475 775);
DISPLAY INVISIBLE (-1475 775);
FORCEPROP 1 LAST HDL_POWER GND
J 1
(-1450 700);
DISPLAY 0.872340 (-1450 700);
PAINT GREEN (-1450 700);
DISPLAY INVISIBLE (-1450 700);
FORCEPROP 1 LAST PATH I12
J 0
(-1400 775);
DISPLAY 0.872340 (-1400 775);
PAINT AQUA (-1400 775);
DISPLAY INVISIBLE (-1400 775);
FORCEADD Q_RES..2
(-1475 1075);
FORCEPROP 1 LAST LOCATION R1083
J 0
(-1430 1200);
DISPLAY 0.978723 (-1430 1200);
FORCEPROP 0 LAST $SEC 1
J 0
(-1425 1250);
DISPLAY 0.680851 (-1425 1250);
PAINT MONO (-1425 1250);
DISPLAY INVISIBLE (-1425 1250);
FORCEPROP 0 LAST CDS_SEC 1
J 0
(-1425 1250);
DISPLAY 0.680851 (-1425 1250);
DISPLAY INVISIBLE (-1425 1250);
FORCEPROP 1 LASTPIN (-1475 1175) $PN 1
J 0
(-1470 1137);
DISPLAY 0.787234 (-1470 1137);
PAINT MONO (-1470 1137);
FORCEPROP 1 LASTPIN (-1475 975) $PN 2
J 0
(-1470 985);
DISPLAY 0.787234 (-1470 985);
PAINT MONO (-1470 985);
FORCEPROP 1 LAST TOLERANCE 5%
J 0
(-1430 1100);
DISPLAY 0.978723 (-1430 1100);
FORCEPROP 1 LAST MATERIAL CHIP
J 0
(-1435 1000);
DISPLAY 0.978723 (-1435 1000);
FORCEPROP 1 LAST WATTAGE 1/20W
J 0
(-1435 1050);
DISPLAY 0.978723 (-1435 1050);
FORCEPROP 1 LAST VALUE 0
J 0
(-1430 1150);
DISPLAY 0.978723 (-1430 1150);
FORCEPROP 1 LAST PACK_TYPE 0201LF
J 0
(-1435 900);
DISPLAY 0.978723 (-1435 900);
FORCEPROP 2 LAST CDS_LIB pure_quanta
J 0
(-1475 1075);
DISPLAY INVISIBLE (-1475 1075);
FORCEPROP 1 LAST PATH I13
J 0
(-1425 1250);
DISPLAY 0.978723 (-1425 1250);
PAINT WHITE (-1425 1250);
DISPLAY INVISIBLE (-1425 1250);
FORCEPROP 1 LAST PART_NUMBER CS00001JE10
J 0
(-1435 950);
DISPLAY 0.978723 (-1435 950);
DISPLAY INVISIBLE (-1435 950);
FORCEADD Q_RES..2
(-1325 1625);
FORCEPROP 1 LAST LOCATION R1084
J 0
(-1280 1750);
DISPLAY 0.978723 (-1280 1750);
FORCEPROP 0 LAST $SEC 1
J 0
(-1275 1800);
DISPLAY 0.680851 (-1275 1800);
PAINT MONO (-1275 1800);
DISPLAY INVISIBLE (-1275 1800);
FORCEPROP 0 LAST CDS_SEC 1
J 0
(-1275 1800);
DISPLAY 0.680851 (-1275 1800);
DISPLAY INVISIBLE (-1275 1800);
FORCEPROP 1 LASTPIN (-1325 1725) $PN 1
J 0
(-1320 1687);
DISPLAY 0.787234 (-1320 1687);
PAINT MONO (-1320 1687);
FORCEPROP 1 LASTPIN (-1325 1525) $PN 2
J 0
(-1320 1535);
DISPLAY 0.787234 (-1320 1535);
PAINT MONO (-1320 1535);
FORCEPROP 1 LAST MATERIAL CHIP
J 0
(-1285 1550);
DISPLAY 0.978723 (-1285 1550);
FORCEPROP 1 LAST TOLERANCE 5%
J 0
(-1280 1650);
DISPLAY 0.978723 (-1280 1650);
FORCEPROP 1 LAST PACK_TYPE 0201LF
J 0
(-1285 1450);
DISPLAY 0.978723 (-1285 1450);
FORCEPROP 1 LAST VALUE 0
J 0
(-1280 1700);
DISPLAY 0.978723 (-1280 1700);
FORCEPROP 1 LAST WATTAGE 1/20W
J 0
(-1285 1600);
DISPLAY 0.978723 (-1285 1600);
FORCEPROP 2 LAST CDS_LIB pure_quanta
J 0
(-1325 1625);
DISPLAY INVISIBLE (-1325 1625);
FORCEPROP 1 LAST PATH I14
J 0
(-1275 1800);
DISPLAY 0.978723 (-1275 1800);
PAINT WHITE (-1275 1800);
DISPLAY INVISIBLE (-1275 1800);
FORCEPROP 1 LAST PART_NUMBER CS00001JE10
J 0
(-1285 1500);
DISPLAY 0.978723 (-1285 1500);
DISPLAY INVISIBLE (-1285 1500);
FORCEADD UNIVERSAL_GND..1
(-1325 1325);
FORCEPROP 3 LASTPIN (-1325 1375) SIG_NAME GND\g
J 0
(-1315 1385);
DISPLAY 0.659574 (-1315 1385);
PAINT MONO (-1315 1385);
DISPLAY INVISIBLE (-1315 1385);
FORCEPROP 2 LAST CDS_LIB pure_quanta_power
J 0
(-1325 1325);
DISPLAY INVISIBLE (-1325 1325);
FORCEPROP 1 LAST HDL_POWER GND
J 1
(-1300 1250);
DISPLAY 0.872340 (-1300 1250);
PAINT GREEN (-1300 1250);
DISPLAY INVISIBLE (-1300 1250);
FORCEPROP 1 LAST PATH I15
J 0
(-1250 1325);
DISPLAY 0.872340 (-1250 1325);
PAINT AQUA (-1250 1325);
DISPLAY INVISIBLE (-1250 1325);
FORCEADD UNIVERSAL_GND..1
(-1100 1875);
FORCEPROP 3 LASTPIN (-1100 1925) SIG_NAME GND\g
J 0
(-1090 1935);
DISPLAY 0.659574 (-1090 1935);
PAINT MONO (-1090 1935);
DISPLAY INVISIBLE (-1090 1935);
FORCEPROP 2 LAST CDS_LIB pure_quanta_power
J 0
(-1100 1875);
DISPLAY INVISIBLE (-1100 1875);
FORCEPROP 1 LAST HDL_POWER GND
J 1
(-1075 1800);
DISPLAY 0.872340 (-1075 1800);
PAINT GREEN (-1075 1800);
DISPLAY INVISIBLE (-1075 1800);
FORCEPROP 1 LAST PATH I16
J 0
(-1025 1875);
DISPLAY 0.872340 (-1025 1875);
PAINT AQUA (-1025 1875);
DISPLAY INVISIBLE (-1025 1875);
FORCEADD PT5161LRS..5
(-2450 3400);
FORCEPROP 1 LAST LOCATION U6012
J 0
(-2800 5725);
DISPLAY 0.723404 (-2800 5725);
PAINT SKYBLUE (-2800 5725);
FORCEPROP 0 LAST $SEC 5
J 0
(-2800 5875);
DISPLAY 0.680851 (-2800 5875);
PAINT MONO (-2800 5875);
DISPLAY INVISIBLE (-2800 5875);
FORCEPROP 0 LAST CDS_SEC 5
J 0
(-2800 5875);
DISPLAY 0.680851 (-2800 5875);
DISPLAY INVISIBLE (-2800 5875);
FORCEPROP 0 LASTPIN (-2950 5400) $PN AC13
J 2
(-2960 5410);
DISPLAY 0.680851 (-2960 5410);
PAINT MONO (-2960 5410);
FORCEPROP 0 LASTPIN (-2950 5350) $PN AC22
J 2
(-2960 5360);
DISPLAY 0.680851 (-2960 5360);
PAINT MONO (-2960 5360);
FORCEPROP 0 LASTPIN (-2950 5300) $PN AC32
J 2
(-2960 5310);
DISPLAY 0.680851 (-2960 5310);
PAINT MONO (-2960 5310);
FORCEPROP 0 LASTPIN (-2950 5250) $PN AC4
J 2
(-2960 5260);
DISPLAY 0.680851 (-2960 5260);
PAINT MONO (-2960 5260);
FORCEPROP 0 LASTPIN (-2950 5200) $PN AD2
J 2
(-2960 5210);
DISPLAY 0.680851 (-2960 5210);
PAINT MONO (-2960 5210);
FORCEPROP 0 LASTPIN (-2950 5150) $PN AD34
J 2
(-2960 5160);
DISPLAY 0.680851 (-2960 5160);
PAINT MONO (-2960 5160);
FORCEPROP 0 LASTPIN (-2950 5100) $PN AE1
J 2
(-2960 5110);
DISPLAY 0.680851 (-2960 5110);
PAINT MONO (-2960 5110);
FORCEPROP 0 LASTPIN (-2950 5050) $PN AE35
J 2
(-2960 5060);
DISPLAY 0.680851 (-2960 5060);
PAINT MONO (-2960 5060);
FORCEPROP 0 LASTPIN (-2950 5000) $PN AK13
J 2
(-2960 5010);
DISPLAY 0.680851 (-2960 5010);
PAINT MONO (-2960 5010);
FORCEPROP 0 LASTPIN (-2950 4950) $PN AK22
J 2
(-2960 4960);
DISPLAY 0.680851 (-2960 4960);
PAINT MONO (-2960 4960);
FORCEPROP 0 LASTPIN (-2950 4900) $PN AK32
J 2
(-2960 4910);
DISPLAY 0.680851 (-2960 4910);
PAINT MONO (-2960 4910);
FORCEPROP 0 LASTPIN (-2950 4850) $PN AK4
J 2
(-2960 4860);
DISPLAY 0.680851 (-2960 4860);
PAINT MONO (-2960 4860);
FORCEPROP 0 LASTPIN (-2950 4800) $PN AL2
J 2
(-2960 4810);
DISPLAY 0.680851 (-2960 4810);
PAINT MONO (-2960 4810);
FORCEPROP 0 LASTPIN (-2950 4750) $PN AL34
J 2
(-2960 4760);
DISPLAY 0.680851 (-2960 4760);
PAINT MONO (-2960 4760);
FORCEPROP 0 LASTPIN (-2950 4700) $PN AM1
J 2
(-2960 4710);
DISPLAY 0.680851 (-2960 4710);
PAINT MONO (-2960 4710);
FORCEPROP 0 LASTPIN (-2950 4650) $PN AM35
J 2
(-2960 4660);
DISPLAY 0.680851 (-2960 4660);
PAINT MONO (-2960 4660);
FORCEPROP 0 LASTPIN (-2950 4600) $PN AU13
J 2
(-2960 4610);
DISPLAY 0.680851 (-2960 4610);
PAINT MONO (-2960 4610);
FORCEPROP 0 LASTPIN (-2950 4550) $PN AU22
J 2
(-2960 4560);
DISPLAY 0.680851 (-2960 4560);
PAINT MONO (-2960 4560);
FORCEPROP 0 LASTPIN (-2950 4500) $PN AU32
J 2
(-2960 4510);
DISPLAY 0.680851 (-2960 4510);
PAINT MONO (-2960 4510);
FORCEPROP 0 LASTPIN (-2950 4450) $PN AU4
J 2
(-2960 4460);
DISPLAY 0.680851 (-2960 4460);
PAINT MONO (-2960 4460);
FORCEPROP 0 LASTPIN (-2950 4400) $PN AV2
J 2
(-2960 4410);
DISPLAY 0.680851 (-2960 4410);
PAINT MONO (-2960 4410);
FORCEPROP 0 LASTPIN (-2950 4350) $PN AV34
J 2
(-2960 4360);
DISPLAY 0.680851 (-2960 4360);
PAINT MONO (-2960 4360);
FORCEPROP 0 LASTPIN (-2950 4300) $PN AW1
J 2
(-2960 4310);
DISPLAY 0.680851 (-2960 4310);
PAINT MONO (-2960 4310);
FORCEPROP 0 LASTPIN (-2950 4250) $PN AW35
J 2
(-2960 4260);
DISPLAY 0.680851 (-2960 4260);
PAINT MONO (-2960 4260);
FORCEPROP 0 LASTPIN (-2950 4200) $PN B19
J 2
(-2960 4210);
DISPLAY 0.680851 (-2960 4210);
PAINT MONO (-2960 4210);
FORCEPROP 0 LASTPIN (-2950 4150) $PN BD13
J 2
(-2960 4160);
DISPLAY 0.680851 (-2960 4160);
PAINT MONO (-2960 4160);
FORCEPROP 0 LASTPIN (-2950 4100) $PN BD22
J 2
(-2960 4110);
DISPLAY 0.680851 (-2960 4110);
PAINT MONO (-2960 4110);
FORCEPROP 0 LASTPIN (-2950 4050) $PN BD32
J 2
(-2960 4060);
DISPLAY 0.680851 (-2960 4060);
PAINT MONO (-2960 4060);
FORCEPROP 0 LASTPIN (-2950 4000) $PN BD4
J 2
(-2960 4010);
DISPLAY 0.680851 (-2960 4010);
PAINT MONO (-2960 4010);
FORCEPROP 0 LASTPIN (-2950 3950) $PN BE2
J 2
(-2960 3960);
DISPLAY 0.680851 (-2960 3960);
PAINT MONO (-2960 3960);
FORCEPROP 0 LASTPIN (-2950 3900) $PN BE34
J 2
(-2960 3910);
DISPLAY 0.680851 (-2960 3910);
PAINT MONO (-2960 3910);
FORCEPROP 0 LASTPIN (-2950 3850) $PN BF1
J 2
(-2960 3860);
DISPLAY 0.680851 (-2960 3860);
PAINT MONO (-2960 3860);
FORCEPROP 0 LASTPIN (-2950 3800) $PN BF35
J 2
(-2960 3810);
DISPLAY 0.680851 (-2960 3810);
PAINT MONO (-2960 3810);
FORCEPROP 0 LASTPIN (-2950 3750) $PN BL13
J 2
(-2960 3760);
DISPLAY 0.680851 (-2960 3760);
PAINT MONO (-2960 3760);
FORCEPROP 0 LASTPIN (-2950 3700) $PN BL22
J 2
(-2960 3710);
DISPLAY 0.680851 (-2960 3710);
PAINT MONO (-2960 3710);
FORCEPROP 0 LASTPIN (-2950 3650) $PN BL32
J 2
(-2960 3660);
DISPLAY 0.680851 (-2960 3660);
PAINT MONO (-2960 3660);
FORCEPROP 0 LASTPIN (-2950 3600) $PN BL4
J 2
(-2960 3610);
DISPLAY 0.680851 (-2960 3610);
PAINT MONO (-2960 3610);
FORCEPROP 0 LASTPIN (-2950 3550) $PN BM2
J 2
(-2960 3560);
DISPLAY 0.680851 (-2960 3560);
PAINT MONO (-2960 3560);
FORCEPROP 0 LASTPIN (-2950 3500) $PN BM34
J 2
(-2960 3510);
DISPLAY 0.680851 (-2960 3510);
PAINT MONO (-2960 3510);
FORCEPROP 0 LASTPIN (-2950 3450) $PN BN1
J 2
(-2960 3460);
DISPLAY 0.680851 (-2960 3460);
PAINT MONO (-2960 3460);
FORCEPROP 0 LASTPIN (-2950 3400) $PN BN35
J 2
(-2960 3410);
DISPLAY 0.680851 (-2960 3410);
PAINT MONO (-2960 3410);
FORCEPROP 0 LASTPIN (-2950 3350) $PN BV13
J 2
(-2960 3360);
DISPLAY 0.680851 (-2960 3360);
PAINT MONO (-2960 3360);
FORCEPROP 0 LASTPIN (-2950 3300) $PN BV22
J 2
(-2960 3310);
DISPLAY 0.680851 (-2960 3310);
PAINT MONO (-2960 3310);
FORCEPROP 0 LASTPIN (-2950 3250) $PN BV32
J 2
(-2960 3260);
DISPLAY 0.680851 (-2960 3260);
PAINT MONO (-2960 3260);
FORCEPROP 0 LASTPIN (-2950 3200) $PN BV4
J 2
(-2960 3210);
DISPLAY 0.680851 (-2960 3210);
PAINT MONO (-2960 3210);
FORCEPROP 0 LASTPIN (-2950 3150) $PN BW2
J 2
(-2960 3160);
DISPLAY 0.680851 (-2960 3160);
PAINT MONO (-2960 3160);
FORCEPROP 0 LASTPIN (-2950 3100) $PN BW34
J 2
(-2960 3110);
DISPLAY 0.680851 (-2960 3110);
PAINT MONO (-2960 3110);
FORCEPROP 0 LASTPIN (-2950 3050) $PN BY1
J 2
(-2960 3060);
DISPLAY 0.680851 (-2960 3060);
PAINT MONO (-2960 3060);
FORCEPROP 0 LASTPIN (-2950 3000) $PN BY35
J 2
(-2960 3010);
DISPLAY 0.680851 (-2960 3010);
PAINT MONO (-2960 3010);
FORCEPROP 0 LASTPIN (-2950 2950) $PN CE13
J 2
(-2960 2960);
DISPLAY 0.680851 (-2960 2960);
PAINT MONO (-2960 2960);
FORCEPROP 0 LASTPIN (-2950 2900) $PN CE22
J 2
(-2960 2910);
DISPLAY 0.680851 (-2960 2910);
PAINT MONO (-2960 2910);
FORCEPROP 0 LASTPIN (-2950 2850) $PN CE32
J 2
(-2960 2860);
DISPLAY 0.680851 (-2960 2860);
PAINT MONO (-2960 2860);
FORCEPROP 0 LASTPIN (-2950 2800) $PN CE4
J 2
(-2960 2810);
DISPLAY 0.680851 (-2960 2810);
PAINT MONO (-2960 2810);
FORCEPROP 0 LASTPIN (-2950 2750) $PN CF2
J 2
(-2960 2760);
DISPLAY 0.680851 (-2960 2760);
PAINT MONO (-2960 2760);
FORCEPROP 0 LASTPIN (-2950 2700) $PN CF34
J 2
(-2960 2710);
DISPLAY 0.680851 (-2960 2710);
PAINT MONO (-2960 2710);
FORCEPROP 0 LASTPIN (-2950 2650) $PN CG1
J 2
(-2960 2660);
DISPLAY 0.680851 (-2960 2660);
PAINT MONO (-2960 2660);
FORCEPROP 0 LASTPIN (-2950 2600) $PN CG35
J 2
(-2960 2610);
DISPLAY 0.680851 (-2960 2610);
PAINT MONO (-2960 2610);
FORCEPROP 0 LASTPIN (-2950 2550) $PN CM13
J 2
(-2960 2560);
DISPLAY 0.680851 (-2960 2560);
PAINT MONO (-2960 2560);
FORCEPROP 0 LASTPIN (-2950 2500) $PN CM22
J 2
(-2960 2510);
DISPLAY 0.680851 (-2960 2510);
PAINT MONO (-2960 2510);
FORCEPROP 0 LASTPIN (-2950 2450) $PN CM32
J 2
(-2960 2460);
DISPLAY 0.680851 (-2960 2460);
PAINT MONO (-2960 2460);
FORCEPROP 0 LASTPIN (-2950 2400) $PN CM4
J 2
(-2960 2410);
DISPLAY 0.680851 (-2960 2410);
PAINT MONO (-2960 2410);
FORCEPROP 0 LASTPIN (-2950 2350) $PN CN2
J 2
(-2960 2360);
DISPLAY 0.680851 (-2960 2360);
PAINT MONO (-2960 2360);
FORCEPROP 0 LASTPIN (-2950 2300) $PN CN34
J 2
(-2960 2310);
DISPLAY 0.680851 (-2960 2310);
PAINT MONO (-2960 2310);
FORCEPROP 0 LASTPIN (-2950 2250) $PN CP1
J 2
(-2960 2260);
DISPLAY 0.680851 (-2960 2260);
PAINT MONO (-2960 2260);
FORCEPROP 0 LASTPIN (-2950 2200) $PN CP35
J 2
(-2960 2210);
DISPLAY 0.680851 (-2960 2210);
PAINT MONO (-2960 2210);
FORCEPROP 0 LASTPIN (-2950 2150) $PN CW13
J 2
(-2960 2160);
DISPLAY 0.680851 (-2960 2160);
PAINT MONO (-2960 2160);
FORCEPROP 0 LASTPIN (-2950 2100) $PN CW22
J 2
(-2960 2110);
DISPLAY 0.680851 (-2960 2110);
PAINT MONO (-2960 2110);
FORCEPROP 0 LASTPIN (-2950 2050) $PN CW32
J 2
(-2960 2060);
DISPLAY 0.680851 (-2960 2060);
PAINT MONO (-2960 2060);
FORCEPROP 0 LASTPIN (-2950 2000) $PN CW4
J 2
(-2960 2010);
DISPLAY 0.680851 (-2960 2010);
PAINT MONO (-2960 2010);
FORCEPROP 0 LASTPIN (-2950 1950) $PN CY2
J 2
(-2960 1960);
DISPLAY 0.680851 (-2960 1960);
PAINT MONO (-2960 1960);
FORCEPROP 0 LASTPIN (-2950 1900) $PN CY34
J 2
(-2960 1910);
DISPLAY 0.680851 (-2960 1910);
PAINT MONO (-2960 1910);
FORCEPROP 0 LASTPIN (-2950 1850) $PN DA1
J 2
(-2960 1860);
DISPLAY 0.680851 (-2960 1860);
PAINT MONO (-2960 1860);
FORCEPROP 0 LASTPIN (-2950 1800) $PN DA35
J 2
(-2960 1810);
DISPLAY 0.680851 (-2960 1810);
PAINT MONO (-2960 1810);
FORCEPROP 0 LASTPIN (-2950 1750) $PN DF13
J 2
(-2960 1760);
DISPLAY 0.680851 (-2960 1760);
PAINT MONO (-2960 1760);
FORCEPROP 0 LASTPIN (-2950 1700) $PN DF22
J 2
(-2960 1710);
DISPLAY 0.680851 (-2960 1710);
PAINT MONO (-2960 1710);
FORCEPROP 0 LASTPIN (-2950 1650) $PN DF32
J 2
(-2960 1660);
DISPLAY 0.680851 (-2960 1660);
PAINT MONO (-2960 1660);
FORCEPROP 0 LASTPIN (-2950 1600) $PN DF4
J 2
(-2960 1610);
DISPLAY 0.680851 (-2960 1610);
PAINT MONO (-2960 1610);
FORCEPROP 0 LASTPIN (-2950 1550) $PN DG2
J 2
(-2960 1560);
DISPLAY 0.680851 (-2960 1560);
PAINT MONO (-2960 1560);
FORCEPROP 0 LASTPIN (-2950 1500) $PN DG34
J 2
(-2960 1510);
DISPLAY 0.680851 (-2960 1510);
PAINT MONO (-2960 1510);
FORCEPROP 0 LASTPIN (-2950 1450) $PN DH1
J 2
(-2960 1460);
DISPLAY 0.680851 (-2960 1460);
PAINT MONO (-2960 1460);
FORCEPROP 0 LASTPIN (-2950 1400) $PN DH35
J 2
(-2960 1410);
DISPLAY 0.680851 (-2960 1410);
PAINT MONO (-2960 1410);
FORCEPROP 0 LASTPIN (-2950 1350) $PN DN13
J 2
(-2960 1360);
DISPLAY 0.680851 (-2960 1360);
PAINT MONO (-2960 1360);
FORCEPROP 0 LASTPIN (-2000 5400) $PN DN22
J 0
(-1990 5410);
DISPLAY 0.680851 (-1990 5410);
PAINT MONO (-1990 5410);
FORCEPROP 0 LASTPIN (-2000 5350) $PN DN32
J 0
(-1990 5360);
DISPLAY 0.680851 (-1990 5360);
PAINT MONO (-1990 5360);
FORCEPROP 0 LASTPIN (-2000 5300) $PN DN4
J 0
(-1990 5310);
DISPLAY 0.680851 (-1990 5310);
PAINT MONO (-1990 5310);
FORCEPROP 0 LASTPIN (-2000 5250) $PN DP2
J 0
(-1990 5260);
DISPLAY 0.680851 (-1990 5260);
PAINT MONO (-1990 5260);
FORCEPROP 0 LASTPIN (-2000 5200) $PN DP34
J 0
(-1990 5210);
DISPLAY 0.680851 (-1990 5210);
PAINT MONO (-1990 5210);
FORCEPROP 0 LASTPIN (-2000 5150) $PN DR1
J 0
(-1990 5160);
DISPLAY 0.680851 (-1990 5160);
PAINT MONO (-1990 5160);
FORCEPROP 0 LASTPIN (-2000 5100) $PN DR35
J 0
(-1990 5110);
DISPLAY 0.680851 (-1990 5110);
PAINT MONO (-1990 5110);
FORCEPROP 0 LASTPIN (-2000 5050) $PN DY13
J 0
(-1990 5060);
DISPLAY 0.680851 (-1990 5060);
PAINT MONO (-1990 5060);
FORCEPROP 0 LASTPIN (-2000 5000) $PN DY22
J 0
(-1990 5010);
DISPLAY 0.680851 (-1990 5010);
PAINT MONO (-1990 5010);
FORCEPROP 0 LASTPIN (-2000 4950) $PN DY32
J 0
(-1990 4960);
DISPLAY 0.680851 (-1990 4960);
PAINT MONO (-1990 4960);
FORCEPROP 0 LASTPIN (-2000 4900) $PN DY4
J 0
(-1990 4910);
DISPLAY 0.680851 (-1990 4910);
PAINT MONO (-1990 4910);
FORCEPROP 0 LASTPIN (-2000 4850) $PN E14
J 0
(-1990 4860);
DISPLAY 0.680851 (-1990 4860);
PAINT MONO (-1990 4860);
FORCEPROP 0 LASTPIN (-2000 4800) $PN E27
J 0
(-1990 4810);
DISPLAY 0.680851 (-1990 4810);
PAINT MONO (-1990 4810);
FORCEPROP 0 LASTPIN (-2000 4750) $PN E33
J 0
(-1990 4760);
DISPLAY 0.680851 (-1990 4760);
PAINT MONO (-1990 4760);
FORCEPROP 0 LASTPIN (-2000 4700) $PN EA2
J 0
(-1990 4710);
DISPLAY 0.680851 (-1990 4710);
PAINT MONO (-1990 4710);
FORCEPROP 0 LASTPIN (-2000 4650) $PN EA34
J 0
(-1990 4660);
DISPLAY 0.680851 (-1990 4660);
PAINT MONO (-1990 4660);
FORCEPROP 0 LASTPIN (-2000 4600) $PN EB1
J 0
(-1990 4610);
DISPLAY 0.680851 (-1990 4610);
PAINT MONO (-1990 4610);
FORCEPROP 0 LASTPIN (-2000 4550) $PN EB35
J 0
(-1990 4560);
DISPLAY 0.680851 (-1990 4560);
PAINT MONO (-1990 4560);
FORCEPROP 0 LASTPIN (-2000 4500) $PN EG13
J 0
(-1990 4510);
DISPLAY 0.680851 (-1990 4510);
PAINT MONO (-1990 4510);
FORCEPROP 0 LASTPIN (-2000 4450) $PN EG22
J 0
(-1990 4460);
DISPLAY 0.680851 (-1990 4460);
PAINT MONO (-1990 4460);
FORCEPROP 0 LASTPIN (-2000 4400) $PN EG32
J 0
(-1990 4410);
DISPLAY 0.680851 (-1990 4410);
PAINT MONO (-1990 4410);
FORCEPROP 0 LASTPIN (-2000 4350) $PN EG4
J 0
(-1990 4360);
DISPLAY 0.680851 (-1990 4360);
PAINT MONO (-1990 4360);
FORCEPROP 0 LASTPIN (-2000 4300) $PN EH2
J 0
(-1990 4310);
DISPLAY 0.680851 (-1990 4310);
PAINT MONO (-1990 4310);
FORCEPROP 0 LASTPIN (-2000 4250) $PN EH34
J 0
(-1990 4260);
DISPLAY 0.680851 (-1990 4260);
PAINT MONO (-1990 4260);
FORCEPROP 0 LASTPIN (-2000 4200) $PN EJ1
J 0
(-1990 4210);
DISPLAY 0.680851 (-1990 4210);
PAINT MONO (-1990 4210);
FORCEPROP 0 LASTPIN (-2000 4150) $PN EJ35
J 0
(-1990 4160);
DISPLAY 0.680851 (-1990 4160);
PAINT MONO (-1990 4160);
FORCEPROP 0 LASTPIN (-2000 4100) $PN EP13
J 0
(-1990 4110);
DISPLAY 0.680851 (-1990 4110);
PAINT MONO (-1990 4110);
FORCEPROP 0 LASTPIN (-2000 4050) $PN EP22
J 0
(-1990 4060);
DISPLAY 0.680851 (-1990 4060);
PAINT MONO (-1990 4060);
FORCEPROP 0 LASTPIN (-2000 4000) $PN EP32
J 0
(-1990 4010);
DISPLAY 0.680851 (-1990 4010);
PAINT MONO (-1990 4010);
FORCEPROP 0 LASTPIN (-2000 3950) $PN EP4
J 0
(-1990 3960);
DISPLAY 0.680851 (-1990 3960);
PAINT MONO (-1990 3960);
FORCEPROP 0 LASTPIN (-2000 3900) $PN ER2
J 0
(-1990 3910);
DISPLAY 0.680851 (-1990 3910);
PAINT MONO (-1990 3910);
FORCEPROP 0 LASTPIN (-2000 3850) $PN ER34
J 0
(-1990 3860);
DISPLAY 0.680851 (-1990 3860);
PAINT MONO (-1990 3860);
FORCEPROP 0 LASTPIN (-2000 3800) $PN ET1
J 0
(-1990 3810);
DISPLAY 0.680851 (-1990 3810);
PAINT MONO (-1990 3810);
FORCEPROP 0 LASTPIN (-2000 3750) $PN ET35
J 0
(-1990 3760);
DISPLAY 0.680851 (-1990 3760);
PAINT MONO (-1990 3760);
FORCEPROP 0 LASTPIN (-2000 3700) $PN FA15
J 0
(-1990 3710);
DISPLAY 0.680851 (-1990 3710);
PAINT MONO (-1990 3710);
FORCEPROP 0 LASTPIN (-2000 3650) $PN FA32
J 0
(-1990 3660);
DISPLAY 0.680851 (-1990 3660);
PAINT MONO (-1990 3660);
FORCEPROP 0 LASTPIN (-2000 3600) $PN FB2
J 0
(-1990 3610);
DISPLAY 0.680851 (-1990 3610);
PAINT MONO (-1990 3610);
FORCEPROP 0 LASTPIN (-2000 3550) $PN FB34
J 0
(-1990 3560);
DISPLAY 0.680851 (-1990 3560);
PAINT MONO (-1990 3560);
FORCEPROP 0 LASTPIN (-2000 3500) $PN FC19
J 0
(-1990 3510);
DISPLAY 0.680851 (-1990 3510);
PAINT MONO (-1990 3510);
FORCEPROP 0 LASTPIN (-2000 3450) $PN FC23
J 0
(-1990 3460);
DISPLAY 0.680851 (-1990 3460);
PAINT MONO (-1990 3460);
FORCEPROP 0 LASTPIN (-2000 3400) $PN FC25
J 0
(-1990 3410);
DISPLAY 0.680851 (-1990 3410);
PAINT MONO (-1990 3410);
FORCEPROP 0 LASTPIN (-2000 3350) $PN FC28
J 0
(-1990 3360);
DISPLAY 0.680851 (-1990 3360);
PAINT MONO (-1990 3360);
FORCEPROP 0 LASTPIN (-2000 3300) $PN FC3
J 0
(-1990 3310);
DISPLAY 0.680851 (-1990 3310);
PAINT MONO (-1990 3310);
FORCEPROP 0 LASTPIN (-2000 3250) $PN FC6
J 0
(-1990 3260);
DISPLAY 0.680851 (-1990 3260);
PAINT MONO (-1990 3260);
FORCEPROP 0 LASTPIN (-2000 3200) $PN FC9
J 0
(-1990 3210);
DISPLAY 0.680851 (-1990 3210);
PAINT MONO (-1990 3210);
FORCEPROP 0 LASTPIN (-2000 3150) $PN FD1
J 0
(-1990 3160);
DISPLAY 0.680851 (-1990 3160);
PAINT MONO (-1990 3160);
FORCEPROP 0 LASTPIN (-2000 3100) $PN FD35
J 0
(-1990 3110);
DISPLAY 0.680851 (-1990 3110);
PAINT MONO (-1990 3110);
FORCEPROP 0 LASTPIN (-2000 3050) $PN FF14
J 0
(-1990 3060);
DISPLAY 0.680851 (-1990 3060);
PAINT MONO (-1990 3060);
FORCEPROP 0 LASTPIN (-2000 3000) $PN FF21
J 0
(-1990 3010);
DISPLAY 0.680851 (-1990 3010);
PAINT MONO (-1990 3010);
FORCEPROP 0 LASTPIN (-2000 2950) $PN FJ12
J 0
(-1990 2960);
DISPLAY 0.680851 (-1990 2960);
PAINT MONO (-1990 2960);
FORCEPROP 0 LASTPIN (-2000 2900) $PN FJ19
J 0
(-1990 2910);
DISPLAY 0.680851 (-1990 2910);
PAINT MONO (-1990 2910);
FORCEPROP 0 LASTPIN (-2000 2850) $PN H12
J 0
(-1990 2860);
DISPLAY 0.680851 (-1990 2860);
PAINT MONO (-1990 2860);
FORCEPROP 0 LASTPIN (-2000 2800) $PN H16
J 0
(-1990 2810);
DISPLAY 0.680851 (-1990 2810);
PAINT MONO (-1990 2810);
FORCEPROP 0 LASTPIN (-2000 2750) $PN H19
J 0
(-1990 2760);
DISPLAY 0.680851 (-1990 2760);
PAINT MONO (-1990 2760);
FORCEPROP 0 LASTPIN (-2000 2700) $PN H31
J 0
(-1990 2710);
DISPLAY 0.680851 (-1990 2710);
PAINT MONO (-1990 2710);
FORCEPROP 0 LASTPIN (-2000 2650) $PN J22
J 0
(-1990 2660);
DISPLAY 0.680851 (-1990 2660);
PAINT MONO (-1990 2660);
FORCEPROP 0 LASTPIN (-2000 2600) $PN J4
J 0
(-1990 2610);
DISPLAY 0.680851 (-1990 2610);
PAINT MONO (-1990 2610);
FORCEPROP 0 LASTPIN (-2000 2550) $PN K2
J 0
(-1990 2560);
DISPLAY 0.680851 (-1990 2560);
PAINT MONO (-1990 2560);
FORCEPROP 0 LASTPIN (-2000 2500) $PN K34
J 0
(-1990 2510);
DISPLAY 0.680851 (-1990 2510);
PAINT MONO (-1990 2510);
FORCEPROP 0 LASTPIN (-2000 2450) $PN L1
J 0
(-1990 2460);
DISPLAY 0.680851 (-1990 2460);
PAINT MONO (-1990 2460);
FORCEPROP 0 LASTPIN (-2000 2400) $PN L35
J 0
(-1990 2410);
DISPLAY 0.680851 (-1990 2410);
PAINT MONO (-1990 2410);
FORCEPROP 0 LASTPIN (-2000 2350) $PN T13
J 0
(-1990 2360);
DISPLAY 0.680851 (-1990 2360);
PAINT MONO (-1990 2360);
FORCEPROP 0 LASTPIN (-2000 2300) $PN T22
J 0
(-1990 2310);
DISPLAY 0.680851 (-1990 2310);
PAINT MONO (-1990 2310);
FORCEPROP 0 LASTPIN (-2000 2250) $PN T32
J 0
(-1990 2260);
DISPLAY 0.680851 (-1990 2260);
PAINT MONO (-1990 2260);
FORCEPROP 0 LASTPIN (-2000 2200) $PN T4
J 0
(-1990 2210);
DISPLAY 0.680851 (-1990 2210);
PAINT MONO (-1990 2210);
FORCEPROP 0 LASTPIN (-2000 2150) $PN U2
J 0
(-1990 2160);
DISPLAY 0.680851 (-1990 2160);
PAINT MONO (-1990 2160);
FORCEPROP 0 LASTPIN (-2000 2100) $PN U34
J 0
(-1990 2110);
DISPLAY 0.680851 (-1990 2110);
PAINT MONO (-1990 2110);
FORCEPROP 0 LASTPIN (-2000 2050) $PN V1
J 0
(-1990 2060);
DISPLAY 0.680851 (-1990 2060);
PAINT MONO (-1990 2060);
FORCEPROP 0 LASTPIN (-2000 2000) $PN V35
J 0
(-1990 2010);
DISPLAY 0.680851 (-1990 2010);
PAINT MONO (-1990 2010);
FORCEPROP 0 LASTPIN (-2000 1900) $PN A1
J 0
(-1990 1910);
DISPLAY 0.680851 (-1990 1910);
PAINT MONO (-1990 1910);
FORCEPROP 0 LASTPIN (-2000 1850) $PN A35
J 0
(-1990 1860);
DISPLAY 0.680851 (-1990 1860);
PAINT MONO (-1990 1860);
FORCEPROP 0 LASTPIN (-2000 1800) $PN C2
J 0
(-1990 1810);
DISPLAY 0.680851 (-1990 1810);
PAINT MONO (-1990 1810);
FORCEPROP 0 LASTPIN (-2000 1750) $PN C34
J 0
(-1990 1760);
DISPLAY 0.680851 (-1990 1760);
PAINT MONO (-1990 1760);
FORCEPROP 0 LASTPIN (-2000 1700) $PN D1
J 0
(-1990 1710);
DISPLAY 0.680851 (-1990 1710);
PAINT MONO (-1990 1710);
FORCEPROP 0 LASTPIN (-2000 1650) $PN D35
J 0
(-1990 1660);
DISPLAY 0.680851 (-1990 1660);
PAINT MONO (-1990 1660);
FORCEPROP 0 LASTPIN (-2000 1600) $PN FE2
J 0
(-1990 1610);
DISPLAY 0.680851 (-1990 1610);
PAINT MONO (-1990 1610);
FORCEPROP 0 LASTPIN (-2000 1550) $PN FE34
J 0
(-1990 1560);
DISPLAY 0.680851 (-1990 1560);
PAINT MONO (-1990 1560);
FORCEPROP 0 LASTPIN (-2000 1500) $PN FG1
J 0
(-1990 1510);
DISPLAY 0.680851 (-1990 1510);
PAINT MONO (-1990 1510);
FORCEPROP 0 LASTPIN (-2000 1450) $PN FG35
J 0
(-1990 1460);
DISPLAY 0.680851 (-1990 1460);
PAINT MONO (-1990 1460);
FORCEPROP 0 LASTPIN (-2000 1400) $PN FH2
J 0
(-1990 1410);
DISPLAY 0.680851 (-1990 1410);
PAINT MONO (-1990 1410);
FORCEPROP 0 LASTPIN (-2000 1350) $PN FH34
J 0
(-1990 1360);
DISPLAY 0.680851 (-1990 1360);
PAINT MONO (-1990 1360);
FORCEPROP 1 LAST MATERIAL IC
J 0
(-2800 5575);
DISPLAY 0.723404 (-2800 5575);
PAINT GREEN (-2800 5575);
FORCEPROP 2 LAST VALUE PT5161LRS
J 0
(-2800 5775);
DISPLAY 0.680851 (-2800 5775);
FORCEPROP 2 LAST PART_TYPE SMLF
J 0
(-2800 5825);
DISPLAY 0.680851 (-2800 5825);
FORCEPROP 2 LAST CDS_LIB pure_quanta
J 0
(-2450 3400);
DISPLAY INVISIBLE (-2450 3400);
FORCEPROP 1 LAST CDS_LMAN_SYM_OUTLINE -350,2150,300,-2150
J 0
(-2450 3400);
DISPLAY 0.468085 (-2450 3400);
PAINT GREEN (-2450 3400);
DISPLAY INVISIBLE (-2450 3400);
FORCEPROP 1 LAST NEEDS_NO_SIZE TRUE
J 0
(-2450 3400);
DISPLAY 0.723404 (-2450 3400);
PAINT GREEN (-2450 3400);
DISPLAY INVISIBLE (-2450 3400);
FORCEPROP 1 LAST PATH I17
J 0
(-2450 3400);
DISPLAY 0.723404 (-2450 3400);
PAINT GREEN (-2450 3400);
DISPLAY INVISIBLE (-2450 3400);
FORCEPROP 1 LAST PART_NUMBER AJ051610U03
J 0
(-2800 5650);
DISPLAY 0.723404 (-2800 5650);
PAINT GREEN (-2800 5650);
DISPLAY INVISIBLE (-2800 5650);
FORCEADD Q_RES..2
(-7675 3175);
FORCEPROP 1 LAST LOCATION R1082
J 0
(-7630 3300);
DISPLAY 0.978723 (-7630 3300);
PAINT WHITE (-7630 3300);
FORCEPROP 0 LAST $SEC 1
J 0
(-7625 3350);
DISPLAY 0.680851 (-7625 3350);
PAINT MONO (-7625 3350);
DISPLAY INVISIBLE (-7625 3350);
FORCEPROP 0 LAST CDS_SEC 1
J 0
(-7625 3350);
DISPLAY 0.680851 (-7625 3350);
DISPLAY INVISIBLE (-7625 3350);
FORCEPROP 1 LASTPIN (-7675 3275) $PN 1
J 0
(-7670 3237);
DISPLAY 0.787234 (-7670 3237);
PAINT MONO (-7670 3237);
FORCEPROP 1 LASTPIN (-7675 3075) $PN 2
J 0
(-7670 3085);
DISPLAY 0.787234 (-7670 3085);
PAINT MONO (-7670 3085);
FORCEPROP 1 LAST TOLERANCE 1%
J 0
(-7630 3200);
DISPLAY 0.978723 (-7630 3200);
FORCEPROP 1 LAST WATTAGE 1/20W
J 0
(-7635 3150);
DISPLAY 0.978723 (-7635 3150);
FORCEPROP 1 LAST PACK_TYPE 0201LF
J 0
(-7635 3000);
DISPLAY 0.978723 (-7635 3000);
FORCEPROP 1 LAST MATERIAL CHIP
J 0
(-7635 3100);
DISPLAY 0.978723 (-7635 3100);
FORCEPROP 1 LAST VALUE 200
J 0
(-7630 3250);
DISPLAY 0.978723 (-7630 3250);
FORCEPROP 2 LAST CDS_LIB pure_quanta
J 0
(-7675 3175);
DISPLAY INVISIBLE (-7675 3175);
FORCEPROP 1 LAST PATH I18
J 0
(-7625 3350);
DISPLAY 0.978723 (-7625 3350);
PAINT WHITE (-7625 3350);
DISPLAY INVISIBLE (-7625 3350);
FORCEPROP 1 LAST PART_NUMBER CS12001FE12
J 0
(-7635 3050);
DISPLAY 0.978723 (-7635 3050);
DISPLAY INVISIBLE (-7635 3050);
FORCEADD Q_RES..2
(-8700 3725);
FORCEPROP 1 LAST LOCATION R1081
J 0
(-8655 3850);
DISPLAY 0.787234 (-8655 3850);
PAINT SKYBLUE (-8655 3850);
FORCEPROP 0 LAST $SEC 1
J 0
(-8650 3900);
DISPLAY 0.680851 (-8650 3900);
PAINT MONO (-8650 3900);
DISPLAY INVISIBLE (-8650 3900);
FORCEPROP 0 LAST CDS_SEC 1
J 0
(-8650 3900);
DISPLAY 0.680851 (-8650 3900);
DISPLAY INVISIBLE (-8650 3900);
FORCEPROP 1 LASTPIN (-8700 3825) $PN 1
J 0
(-8695 3787);
DISPLAY 0.787234 (-8695 3787);
PAINT MONO (-8695 3787);
FORCEPROP 1 LASTPIN (-8700 3625) $PN 2
J 0
(-8695 3635);
DISPLAY 0.787234 (-8695 3635);
PAINT MONO (-8695 3635);
FORCEPROP 1 LAST WATTAGE 1/20W
J 0
(-8660 3700);
DISPLAY 0.787234 (-8660 3700);
FORCEPROP 1 LAST MATERIAL EMPTY
J 0
(-8660 3650);
DISPLAY 0.787234 (-8660 3650);
PAINT RED (-8660 3650);
FORCEPROP 1 LAST VALUE 1K
J 0
(-8655 3800);
DISPLAY 0.787234 (-8655 3800);
FORCEPROP 1 LAST TOLERANCE 1%
J 0
(-8655 3750);
DISPLAY 0.787234 (-8655 3750);
FORCEPROP 1 LAST PACK_TYPE 0201LF
J 0
(-8660 3550);
DISPLAY 0.787234 (-8660 3550);
FORCEPROP 2 LAST CDS_LIB pure_quanta
J 0
(-8700 3725);
DISPLAY INVISIBLE (-8700 3725);
FORCEPROP 1 LAST PATH I19
J 0
(-8650 3900);
DISPLAY 0.978723 (-8650 3900);
PAINT WHITE (-8650 3900);
DISPLAY INVISIBLE (-8650 3900);
FORCEPROP 1 LAST PART_NUMBER CS21001FE07
J 0
(-8660 3600);
DISPLAY 0.978723 (-8660 3600);
DISPLAY INVISIBLE (-8660 3600);
FORCEADD P1V0..1
(-8700 3950);
FORCEPROP 3 LASTPIN (-8700 3900) SIG_NAME P1V8_CPU0_RT_1D\g
J 0
(-8690 3910);
DISPLAY 0.659574 (-8690 3910);
PAINT MONO (-8690 3910);
DISPLAY INVISIBLE (-8690 3910);
FORCEPROP 1 LAST HDL_POWER P1V8_CPU0_RT_1D
J 1
(-8700 4000);
DISPLAY 0.489362 (-8700 4000);
PAINT SKYBLUE (-8700 4000);
FORCEPROP 2 LAST CDS_LIB pure_quanta_power
J 0
(-8700 3950);
DISPLAY INVISIBLE (-8700 3950);
FORCEPROP 1 LAST PATH I2
J 0
(-8650 3975);
DISPLAY 0.872340 (-8650 3975);
PAINT AQUA (-8650 3975);
DISPLAY INVISIBLE (-8650 3975);
FORCEADD P1V0..1
(-8375 4225);
FORCEPROP 3 LASTPIN (-8375 4175) SIG_NAME P1V8_CPU0_RT2_1A_1D\g
J 0
(-8365 4185);
DISPLAY 0.659574 (-8365 4185);
PAINT MONO (-8365 4185);
DISPLAY INVISIBLE (-8365 4185);
FORCEPROP 1 LAST HDL_POWER P1V8_CPU0_RT2_1A_1D
J 1
(-8375 4275);
DISPLAY 0.489362 (-8375 4275);
PAINT SKYBLUE (-8375 4275);
FORCEPROP 2 LAST CDS_LIB pure_quanta_power
J 0
(-8375 4225);
DISPLAY INVISIBLE (-8375 4225);
FORCEPROP 1 LAST PATH I3
J 0
(-8325 4250);
DISPLAY 0.872340 (-8325 4250);
PAINT AQUA (-8325 4250);
DISPLAY INVISIBLE (-8325 4250);
FORCEADD UNIVERSAL_GND..1
(-7675 2925);
FORCEPROP 3 LASTPIN (-7675 2975) SIG_NAME GND\g
J 0
(-7665 2985);
DISPLAY 0.659574 (-7665 2985);
PAINT MONO (-7665 2985);
DISPLAY INVISIBLE (-7665 2985);
FORCEPROP 2 LAST CDS_LIB pure_quanta_power
J 0
(-7675 2925);
DISPLAY INVISIBLE (-7675 2925);
FORCEPROP 1 LAST HDL_POWER GND
J 1
(-7650 2850);
DISPLAY 0.872340 (-7650 2850);
PAINT GREEN (-7650 2850);
DISPLAY INVISIBLE (-7650 2850);
FORCEPROP 1 LAST PATH I4
J 0
(-7600 2925);
DISPLAY 0.872340 (-7600 2925);
PAINT AQUA (-7600 2925);
DISPLAY INVISIBLE (-7600 2925);
FORCEADD PT5161LRS..4
(-6525 3975);
FORCEPROP 1 LAST LOCATION U6012
J 0
(-6975 4900);
DISPLAY 0.723404 (-6975 4900);
PAINT SKYBLUE (-6975 4900);
FORCEPROP 0 LAST $SEC 4
J 0
(-6975 5050);
DISPLAY 0.680851 (-6975 5050);
PAINT MONO (-6975 5050);
DISPLAY INVISIBLE (-6975 5050);
FORCEPROP 0 LAST CDS_SEC 4
J 0
(-6975 5050);
DISPLAY 0.680851 (-6975 5050);
DISPLAY INVISIBLE (-6975 5050);
FORCEPROP 0 LASTPIN (-7125 4575) $PN BV20
J 2
(-7135 4585);
DISPLAY 0.680851 (-7135 4585);
PAINT MONO (-7135 4585);
FORCEPROP 0 LASTPIN (-7125 4525) $PN CE17
J 2
(-7135 4535);
DISPLAY 0.680851 (-7135 4535);
PAINT MONO (-7135 4535);
FORCEPROP 0 LASTPIN (-7125 4475) $PN CE20
J 2
(-7135 4485);
DISPLAY 0.680851 (-7135 4485);
PAINT MONO (-7135 4485);
FORCEPROP 0 LASTPIN (-7125 4425) $PN CM17
J 2
(-7135 4435);
DISPLAY 0.680851 (-7135 4435);
PAINT MONO (-7135 4435);
FORCEPROP 0 LASTPIN (-7125 4375) $PN CM20
J 2
(-7135 4385);
DISPLAY 0.680851 (-7135 4385);
PAINT MONO (-7135 4385);
FORCEPROP 0 LASTPIN (-7125 3925) $PN BV17
J 2
(-7135 3935);
DISPLAY 0.680851 (-7135 3935);
PAINT MONO (-7135 3935);
FORCEPROP 0 LASTPIN (-5975 4575) $PN AC17
J 0
(-5965 4585);
DISPLAY 0.680851 (-5965 4585);
PAINT MONO (-5965 4585);
FORCEPROP 0 LASTPIN (-5975 4525) $PN AC20
J 0
(-5965 4535);
DISPLAY 0.680851 (-5965 4535);
PAINT MONO (-5965 4535);
FORCEPROP 0 LASTPIN (-5975 4475) $PN AK17
J 0
(-5965 4485);
DISPLAY 0.680851 (-5965 4485);
PAINT MONO (-5965 4485);
FORCEPROP 0 LASTPIN (-5975 4425) $PN AK20
J 0
(-5965 4435);
DISPLAY 0.680851 (-5965 4435);
PAINT MONO (-5965 4435);
FORCEPROP 0 LASTPIN (-5975 4375) $PN AU17
J 0
(-5965 4385);
DISPLAY 0.680851 (-5965 4385);
PAINT MONO (-5965 4385);
FORCEPROP 0 LASTPIN (-5975 4325) $PN AU20
J 0
(-5965 4335);
DISPLAY 0.680851 (-5965 4335);
PAINT MONO (-5965 4335);
FORCEPROP 0 LASTPIN (-5975 4275) $PN BD17
J 0
(-5965 4285);
DISPLAY 0.680851 (-5965 4285);
PAINT MONO (-5965 4285);
FORCEPROP 0 LASTPIN (-5975 4225) $PN BD20
J 0
(-5965 4235);
DISPLAY 0.680851 (-5965 4235);
PAINT MONO (-5965 4235);
FORCEPROP 0 LASTPIN (-5975 4175) $PN DF17
J 0
(-5965 4185);
DISPLAY 0.680851 (-5965 4185);
PAINT MONO (-5965 4185);
FORCEPROP 0 LASTPIN (-5975 4125) $PN DF20
J 0
(-5965 4135);
DISPLAY 0.680851 (-5965 4135);
PAINT MONO (-5965 4135);
FORCEPROP 0 LASTPIN (-5975 4075) $PN DN17
J 0
(-5965 4085);
DISPLAY 0.680851 (-5965 4085);
PAINT MONO (-5965 4085);
FORCEPROP 0 LASTPIN (-5975 4025) $PN DN20
J 0
(-5965 4035);
DISPLAY 0.680851 (-5965 4035);
PAINT MONO (-5965 4035);
FORCEPROP 0 LASTPIN (-5975 3975) $PN DY17
J 0
(-5965 3985);
DISPLAY 0.680851 (-5965 3985);
PAINT MONO (-5965 3985);
FORCEPROP 0 LASTPIN (-5975 3925) $PN DY20
J 0
(-5965 3935);
DISPLAY 0.680851 (-5965 3935);
PAINT MONO (-5965 3935);
FORCEPROP 0 LASTPIN (-5975 3875) $PN EG17
J 0
(-5965 3885);
DISPLAY 0.680851 (-5965 3885);
PAINT MONO (-5965 3885);
FORCEPROP 0 LASTPIN (-5975 3825) $PN EG20
J 0
(-5965 3835);
DISPLAY 0.680851 (-5965 3835);
PAINT MONO (-5965 3835);
FORCEPROP 0 LASTPIN (-5975 3775) $PN EP17
J 0
(-5965 3785);
DISPLAY 0.680851 (-5965 3785);
PAINT MONO (-5965 3785);
FORCEPROP 0 LASTPIN (-5975 3725) $PN EP20
J 0
(-5965 3735);
DISPLAY 0.680851 (-5965 3735);
PAINT MONO (-5965 3735);
FORCEPROP 0 LASTPIN (-5975 3675) $PN T17
J 0
(-5965 3685);
DISPLAY 0.680851 (-5965 3685);
PAINT MONO (-5965 3685);
FORCEPROP 0 LASTPIN (-5975 3625) $PN T20
J 0
(-5965 3635);
DISPLAY 0.680851 (-5965 3635);
PAINT MONO (-5965 3635);
FORCEPROP 0 LASTPIN (-5975 3475) $PN BL17
J 0
(-5965 3485);
DISPLAY 0.680851 (-5965 3485);
PAINT MONO (-5965 3485);
FORCEPROP 0 LASTPIN (-5975 3425) $PN BL20
J 0
(-5965 3435);
DISPLAY 0.680851 (-5965 3435);
PAINT MONO (-5965 3435);
FORCEPROP 0 LASTPIN (-5975 3375) $PN CW17
J 0
(-5965 3385);
DISPLAY 0.680851 (-5965 3385);
PAINT MONO (-5965 3385);
FORCEPROP 0 LASTPIN (-5975 3325) $PN CW20
J 0
(-5965 3335);
DISPLAY 0.680851 (-5965 3335);
PAINT MONO (-5965 3335);
FORCEPROP 0 LASTPIN (-7125 3475) $PN G1
J 2
(-7135 3485);
DISPLAY 0.680851 (-7135 3485);
PAINT MONO (-7135 3485);
FORCEPROP 1 LAST MATERIAL IC
J 0
(-6975 4750);
DISPLAY 0.723404 (-6975 4750);
PAINT GREEN (-6975 4750);
FORCEPROP 2 LAST PART_TYPE SMLF
J 0
(-6975 5000);
DISPLAY 0.680851 (-6975 5000);
FORCEPROP 2 LAST VALUE PT5161LRS
J 0
(-6975 4950);
DISPLAY 0.680851 (-6975 4950);
FORCEPROP 2 LAST CDS_LIB pure_quanta
J 0
(-6525 3975);
DISPLAY INVISIBLE (-6525 3975);
FORCEPROP 1 LAST CDS_LMAN_SYM_OUTLINE -450,750,400,-750
J 0
(-6525 3975);
DISPLAY 0.468085 (-6525 3975);
PAINT GREEN (-6525 3975);
DISPLAY INVISIBLE (-6525 3975);
FORCEPROP 1 LAST NEEDS_NO_SIZE TRUE
J 0
(-6525 3975);
DISPLAY 0.723404 (-6525 3975);
PAINT GREEN (-6525 3975);
DISPLAY INVISIBLE (-6525 3975);
FORCEPROP 1 LAST PATH I6
J 0
(-6525 3975);
DISPLAY 0.723404 (-6525 3975);
PAINT GREEN (-6525 3975);
DISPLAY INVISIBLE (-6525 3975);
FORCEPROP 1 LAST PART_NUMBER AJ051610U03
J 0
(-6975 4825);
DISPLAY 0.723404 (-6975 4825);
PAINT GREEN (-6975 4825);
DISPLAY INVISIBLE (-6975 4825);
FORCEADD P1V0..1
(-4675 3625);
FORCEPROP 3 LASTPIN (-4675 3575) SIG_NAME P0V9_CPU0_RT_2D\g
J 0
(-4665 3585);
DISPLAY 0.659574 (-4665 3585);
PAINT MONO (-4665 3585);
DISPLAY INVISIBLE (-4665 3585);
FORCEPROP 1 LAST HDL_POWER P0V9_CPU0_RT_2D
J 1
(-4675 3675);
DISPLAY 0.489362 (-4675 3675);
PAINT SKYBLUE (-4675 3675);
FORCEPROP 2 LAST CDS_LIB pure_quanta_power
J 0
(-4675 3625);
DISPLAY INVISIBLE (-4675 3625);
FORCEPROP 1 LAST PATH I7
J 0
(-4625 3650);
DISPLAY 0.872340 (-4625 3650);
PAINT AQUA (-4625 3650);
DISPLAY INVISIBLE (-4625 3650);
FORCEADD P1V0..1
(-7800 4675);
FORCEPROP 3 LASTPIN (-7800 4625) SIG_NAME P1V8_CPU0_RT2_1A\g
J 0
(-7790 4635);
DISPLAY 0.659574 (-7790 4635);
PAINT MONO (-7790 4635);
DISPLAY INVISIBLE (-7790 4635);
FORCEPROP 1 LAST HDL_POWER P1V8_CPU0_RT2_1A
J 1
(-7800 4725);
DISPLAY 0.489362 (-7800 4725);
PAINT SKYBLUE (-7800 4725);
FORCEPROP 2 LAST CDS_LIB pure_quanta_power
J 0
(-7800 4675);
DISPLAY INVISIBLE (-7800 4675);
FORCEPROP 1 LAST PATH I8
J 0
(-7750 4700);
DISPLAY 0.872340 (-7750 4700);
PAINT AQUA (-7750 4700);
DISPLAY INVISIBLE (-7750 4700);
FORCEADD VCC_CORE..1
(-5275 4375);
FORCEPROP 3 LASTPIN (-5275 4325) SIG_NAME P0V9_CPU0_RT2_2A_2D\g
J 0
(-5265 4335);
DISPLAY 0.659574 (-5265 4335);
PAINT MONO (-5265 4335);
DISPLAY INVISIBLE (-5265 4335);
FORCEPROP 1 LAST HDL_POWER P0V9_CPU0_RT2_2A_2D
J 1
(-5275 4425);
DISPLAY 0.617021 (-5275 4425);
PAINT SKYBLUE (-5275 4425);
FORCEPROP 2 LAST CDS_LIB pure_quanta_power
J 0
(-5275 4375);
DISPLAY INVISIBLE (-5275 4375);
FORCEPROP 1 LAST PATH I9
J 0
(-5225 4400);
DISPLAY 0.872340 (-5225 4400);
PAINT AQUA (-5225 4400);
DISPLAY INVISIBLE (-5225 4400);
FORCEADD DNS..2
(-8675 3700);
PAINT RED (-8675 3700);
FORCEPROP 2 LAST CDS_LIB mstr_misc
J 0
(-8675 3700);
DISPLAY INVISIBLE (-8675 3700);
FORCEPROP 1 LAST COMMENT_BODY TRUE
J 0
(-8675 3700);
DISPLAY INVISIBLE (-8675 3700);
FORCEADD QUANTA_TITLE_BLOCK_C..1
(0 0);
FORCEPROP 0 LAST CDS_CON_LAST_MODIFIED Thu Sep 14 16:13:09 2023
J 0
(-1885 15);
DISPLAY INVISIBLE (-1885 15);
FORCEPROP 1 LAST CUSTOM_TXT_CDS <CON_LAST_MODIFIED>
J 0
(-1885 15);
DISPLAY 0.978723 (-1885 15);
FORCEPROP 2 LAST CUSTOM_TXT_CDS <XR_PAGE_TITLE>
J 0
(-7890 5250);
DISPLAY 0.638298 (-7890 5250);
PAINT PINK (-7890 5250);
DISPLAY INVISIBLE (-7890 5250);
FORCEPROP 1 LAST CUSTOM_TXT_CDS <NAME_2>
J 0
(-3175 50);
FORCEPROP 1 LAST CUSTOM_TXT_CDS <NAME_1>
J 0
(-3175 175);
FORCEPROP 1 LAST CUSTOM_TXT_CDS <Q_NUMBER>
J 0
(-1403 103);
DISPLAY 1.212766 (-1403 103);
FORCEPROP 1 LAST CUSTOM_TXT_CDS <Q_PROJ>
J 0
(-2382 102);
DISPLAY 1.212766 (-2382 102);
FORCEPROP 1 LAST CUSTOM_TXT_CDS <Q_REV>
J 0
(-184 103);
DISPLAY 1.212766 (-184 103);
FORCEPROP 1 LAST CUSTOM_TXT_CDS <CON_PAGE_NUM> OF <CON_TOTAL_PAGES>
J 0
(-446 18);
DISPLAY 0.978723 (-446 18);
FORCEPROP 1 LAST Q_TITLE RETIMER_CPU0_P2 POWER(6)
J 0
(-9366 26);
DISPLAY 2.446809 (-9366 26);
PAINT GREEN (-9366 26);
FORCEPROP 2 LAST CDS_LIB pure_quanta
J 0
(0 0);
DISPLAY INVISIBLE (0 0);
FORCEPROP 1 LAST CDS_LMAN_SYM_OUTLINE -9475,6775,100,-125
J 0
(0 0);
DISPLAY 0.468085 (0 0);
PAINT GREEN (0 0);
DISPLAY INVISIBLE (0 0);
FORCEPROP 2 LAST PAGE_BORDER TRUE
J 0
(-7890 5250);
DISPLAY 0.638298 (-7890 5250);
PAINT PINK (-7890 5250);
DISPLAY INVISIBLE (-7890 5250);
FORCEPROP 2 LAST CDS_XR_PAGE_TITLE CR-300 : @T6G_MB_LIB.T6G(SCH_1):PAGE300
J 0
(-7890 5250);
DISPLAY 0.638298 (-7890 5250);
PAINT PINK (-7890 5250);
DISPLAY INVISIBLE (-7890 5250);
FORCEPROP 1 LAST Q_DEPT BU9
J 1
(-3763 49);
DISPLAY 1.957447 (-3763 49);
PAINT GREEN (-3763 49);
DISPLAY INVISIBLE (-3763 49);
FORCEPROP 1 LAST COMMENT_BODY TRUE
J 0
(12 -13);
DISPLAY 0.978723 (12 -13);
PAINT GREEN (12 -13);
DISPLAY INVISIBLE (12 -13);
WIRE 16 -1 (-1475 975)(-1475 825);
WIRE 16 -1 (-1325 1525)(-1325 1375);
WIRE 16 -1 (-8700 3900)(-8700 3825);
WIRE 16 -1 (-7675 3075)(-7675 2975);
WIRE 16 -1 (-7125 3475)(-7675 3475);
WIRE 16 -1 (-7675 3475)(-7675 3275);
WIRE 16 -1 (-7675 3475)(-8700 3475);
FORCEPROP 2 LAST SIG_NAME RT_CPU0_P2_VQPS
J 0
(-7885 3485);
DISPLAY 0.680851 (-7885 3485);
PAINT SKYBLUE (-7885 3485);
FORCEPROP 2 LASTPROP $XRERR UNIQUE?
J 0
(-8125 3485);
DISPLAY 0.638298 (-8125 3485);
PAINT MONO (-8125 3485);
DISPLAY INVISIBLE (-8125 3485);
WIRE 16 -1 (-8700 3625)(-8700 3475);
WIRE 16 -1 (-7125 3925)(-8375 3925);
WIRE 16 -1 (-8375 4175)(-8375 3925);
WIRE 16 -1 (-5725 4225)(-5725 4175);
WIRE 16 -1 (-5725 4275)(-5725 4225);
WIRE 16 -1 (-5975 4225)(-5725 4225);
WIRE 16 -1 (-5725 4175)(-5725 4125);
WIRE 16 -1 (-5725 4175)(-5975 4175);
WIRE 16 -1 (-5725 4125)(-5975 4125);
WIRE 16 -1 (-5725 4275)(-5275 4275);
WIRE 16 -1 (-5975 4275)(-5725 4275);
WIRE 16 -1 (-5275 4275)(-5275 4325);
WIRE 16 -1 (-5750 4425)(-5750 4375);
WIRE 16 -1 (-5750 4475)(-5750 4425);
WIRE 16 -1 (-5975 4425)(-5750 4425);
WIRE 16 -1 (-5750 4375)(-5750 4325);
WIRE 16 -1 (-5975 4375)(-5750 4375);
WIRE 16 -1 (-5750 4325)(-5975 4325);
WIRE 16 -1 (-5750 4525)(-5750 4475);
WIRE 16 -1 (-5975 4475)(-5750 4475);
WIRE 16 -1 (-5750 4575)(-5750 4525);
WIRE 16 -1 (-5975 4525)(-5750 4525);
WIRE 16 -1 (-5750 4575)(-4700 4575);
WIRE 16 -1 (-5975 4575)(-5750 4575);
WIRE 16 -1 (-4700 4575)(-4700 4075);
WIRE 16 -1 (-4700 4575)(-4700 4800);
WIRE 16 -1 (-5725 4075)(-4700 4075);
WIRE 16 -1 (-5725 4075)(-5725 4025);
WIRE 16 -1 (-5725 4075)(-5975 4075);
WIRE 16 -1 (-5725 4025)(-5725 3975);
WIRE 16 -1 (-5975 4025)(-5725 4025);
WIRE 16 -1 (-5725 3975)(-5725 3925);
WIRE 16 -1 (-5975 3975)(-5725 3975);
WIRE 16 -1 (-5725 3925)(-5725 3875);
WIRE 16 -1 (-5975 3925)(-5725 3925);
WIRE 16 -1 (-5725 3875)(-5725 3825);
WIRE 16 -1 (-5975 3875)(-5725 3875);
WIRE 16 -1 (-5725 3825)(-5725 3775);
WIRE 16 -1 (-5975 3825)(-5725 3825);
WIRE 16 -1 (-5725 3775)(-5725 3725);
WIRE 16 -1 (-5975 3775)(-5725 3775);
WIRE 16 -1 (-5725 3725)(-5725 3675);
WIRE 16 -1 (-5975 3725)(-5725 3725);
WIRE 16 -1 (-5725 3675)(-5725 3625);
WIRE 16 -1 (-5975 3675)(-5725 3675);
WIRE 16 -1 (-5725 3625)(-5975 3625);
WIRE 16 -1 (-7125 4575)(-7550 4575);
WIRE 16 -1 (-7550 4575)(-7550 4525);
WIRE 16 -1 (-7550 4575)(-7800 4575);
WIRE 16 -1 (-7800 4575)(-7800 4625);
WIRE 16 -1 (-7125 4525)(-7550 4525);
WIRE 16 -1 (-7550 4525)(-7550 4475);
WIRE 16 -1 (-7125 4475)(-7550 4475);
WIRE 16 -1 (-7550 4475)(-7550 4425);
WIRE 16 -1 (-7125 4425)(-7550 4425);
WIRE 16 -1 (-7550 4425)(-7550 4375);
WIRE 16 -1 (-7550 4375)(-7125 4375);
WIRE 16 -1 (-5650 3425)(-5650 3375);
WIRE 16 -1 (-5650 3475)(-5650 3425);
WIRE 16 -1 (-5975 3425)(-5650 3425);
WIRE 16 -1 (-5650 3375)(-5650 3325);
WIRE 16 -1 (-5975 3375)(-5650 3375);
WIRE 16 -1 (-5650 3325)(-5975 3325);
WIRE 16 -1 (-5650 3475)(-4675 3475);
WIRE 16 -1 (-5975 3475)(-5650 3475);
WIRE 16 -1 (-4675 3575)(-4675 3475);
WIRE 16 -1 (-1800 2050)(-1800 2000);
WIRE 16 -1 (-1800 2100)(-1800 2050);
WIRE 16 -1 (-1800 2050)(-2000 2050);
WIRE 16 -1 (-1800 2000)(-1800 1975);
WIRE 16 -1 (-1800 2000)(-2000 2000);
WIRE 16 -1 (-1800 1975)(-1100 1975);
WIRE 16 -1 (-1800 2150)(-1800 2100);
WIRE 16 -1 (-1800 2100)(-2000 2100);
WIRE 16 -1 (-1800 2200)(-1800 2150);
WIRE 16 -1 (-1800 2150)(-2000 2150);
WIRE 16 -1 (-1100 1975)(-1100 1925);
WIRE 16 -1 (-1800 2250)(-1800 2200);
WIRE 16 -1 (-1800 2200)(-2000 2200);
WIRE 16 -1 (-1800 2300)(-1800 2250);
WIRE 16 -1 (-1800 2250)(-2000 2250);
WIRE 16 -1 (-1800 2350)(-1800 2300);
WIRE 16 -1 (-1800 2300)(-2000 2300);
WIRE 16 -1 (-1800 2400)(-1800 2350);
WIRE 16 -1 (-1800 2350)(-2000 2350);
WIRE 16 -1 (-1800 2450)(-1800 2400);
WIRE 16 -1 (-1800 2400)(-2000 2400);
WIRE 16 -1 (-1800 2500)(-1800 2450);
WIRE 16 -1 (-1800 2450)(-2000 2450);
WIRE 16 -1 (-1800 2550)(-1800 2500);
WIRE 16 -1 (-1800 2500)(-2000 2500);
WIRE 16 -1 (-1800 2600)(-1800 2550);
WIRE 16 -1 (-1800 2550)(-2000 2550);
WIRE 16 -1 (-1800 2650)(-1800 2600);
WIRE 16 -1 (-1800 2600)(-2000 2600);
WIRE 16 -1 (-1800 2700)(-1800 2650);
WIRE 16 -1 (-1800 2650)(-2000 2650);
WIRE 16 -1 (-1800 2750)(-1800 2700);
WIRE 16 -1 (-1800 2700)(-2000 2700);
WIRE 16 -1 (-1800 2800)(-1800 2750);
WIRE 16 -1 (-1800 2750)(-2000 2750);
WIRE 16 -1 (-1800 2850)(-1800 2800);
WIRE 16 -1 (-1800 2800)(-2000 2800);
WIRE 16 -1 (-1800 2900)(-1800 2850);
WIRE 16 -1 (-1800 2850)(-2000 2850);
WIRE 16 -1 (-1800 2950)(-1800 2900);
WIRE 16 -1 (-1800 2900)(-2000 2900);
WIRE 16 -1 (-1800 3000)(-1800 2950);
WIRE 16 -1 (-1800 2950)(-2000 2950);
WIRE 16 -1 (-1800 3050)(-1800 3000);
WIRE 16 -1 (-1800 3000)(-2000 3000);
WIRE 16 -1 (-1800 3100)(-1800 3050);
WIRE 16 -1 (-1800 3050)(-2000 3050);
WIRE 16 -1 (-1800 3150)(-1800 3100);
WIRE 16 -1 (-1800 3100)(-2000 3100);
WIRE 16 -1 (-1800 3200)(-1800 3150);
WIRE 16 -1 (-1800 3150)(-2000 3150);
WIRE 16 -1 (-1800 3250)(-1800 3200);
WIRE 16 -1 (-1800 3200)(-2000 3200);
WIRE 16 -1 (-1800 3300)(-1800 3250);
WIRE 16 -1 (-1800 3250)(-2000 3250);
WIRE 16 -1 (-1800 3350)(-1800 3300);
WIRE 16 -1 (-1800 3300)(-2000 3300);
WIRE 16 -1 (-1800 3400)(-1800 3350);
WIRE 16 -1 (-1800 3350)(-2000 3350);
WIRE 16 -1 (-1800 3450)(-1800 3400);
WIRE 16 -1 (-1800 3400)(-2000 3400);
WIRE 16 -1 (-1800 3500)(-1800 3450);
WIRE 16 -1 (-1800 3450)(-2000 3450);
WIRE 16 -1 (-1800 3550)(-1800 3500);
WIRE 16 -1 (-1800 3500)(-2000 3500);
WIRE 16 -1 (-1800 3600)(-1800 3550);
WIRE 16 -1 (-1800 3550)(-2000 3550);
WIRE 16 -1 (-1800 3650)(-1800 3600);
WIRE 16 -1 (-1800 3600)(-2000 3600);
WIRE 16 -1 (-1800 3700)(-1800 3650);
WIRE 16 -1 (-1800 3650)(-2000 3650);
WIRE 16 -1 (-1800 3750)(-1800 3700);
WIRE 16 -1 (-1800 3700)(-2000 3700);
WIRE 16 -1 (-1800 3800)(-1800 3750);
WIRE 16 -1 (-1800 3750)(-2000 3750);
WIRE 16 -1 (-1800 3850)(-1800 3800);
WIRE 16 -1 (-1800 3800)(-2000 3800);
WIRE 16 -1 (-1800 3900)(-1800 3850);
WIRE 16 -1 (-1800 3850)(-2000 3850);
WIRE 16 -1 (-1800 3950)(-1800 3900);
WIRE 16 -1 (-1800 3900)(-2000 3900);
WIRE 16 -1 (-1800 4000)(-1800 3950);
WIRE 16 -1 (-1800 3950)(-2000 3950);
WIRE 16 -1 (-1800 4050)(-1800 4000);
WIRE 16 -1 (-1800 4000)(-2000 4000);
WIRE 16 -1 (-1800 4100)(-1800 4050);
WIRE 16 -1 (-1800 4050)(-2000 4050);
WIRE 16 -1 (-1800 4150)(-1800 4100);
WIRE 16 -1 (-1800 4100)(-2000 4100);
WIRE 16 -1 (-1800 4200)(-1800 4150);
WIRE 16 -1 (-1800 4150)(-2000 4150);
WIRE 16 -1 (-1800 4250)(-1800 4200);
WIRE 16 -1 (-1800 4200)(-2000 4200);
WIRE 16 -1 (-1800 4300)(-1800 4250);
WIRE 16 -1 (-1800 4250)(-2000 4250);
WIRE 16 -1 (-1800 4350)(-1800 4300);
WIRE 16 -1 (-1800 4300)(-2000 4300);
WIRE 16 -1 (-1800 4400)(-1800 4350);
WIRE 16 -1 (-1800 4350)(-2000 4350);
WIRE 16 -1 (-1800 4450)(-1800 4400);
WIRE 16 -1 (-1800 4400)(-2000 4400);
WIRE 16 -1 (-1800 4500)(-1800 4450);
WIRE 16 -1 (-1800 4450)(-2000 4450);
WIRE 16 -1 (-1800 4550)(-1800 4500);
WIRE 16 -1 (-1800 4500)(-2000 4500);
WIRE 16 -1 (-1800 4600)(-1800 4550);
WIRE 16 -1 (-1800 4550)(-2000 4550);
WIRE 16 -1 (-1800 4650)(-1800 4600);
WIRE 16 -1 (-1800 4600)(-2000 4600);
WIRE 16 -1 (-1800 4700)(-1800 4650);
WIRE 16 -1 (-1800 4650)(-2000 4650);
WIRE 16 -1 (-1800 4750)(-1800 4700);
WIRE 16 -1 (-1800 4700)(-2000 4700);
WIRE 16 -1 (-1800 4800)(-1800 4750);
WIRE 16 -1 (-1800 4750)(-2000 4750);
WIRE 16 -1 (-1800 4850)(-1800 4800);
WIRE 16 -1 (-1800 4800)(-2000 4800);
WIRE 16 -1 (-1800 4900)(-1800 4850);
WIRE 16 -1 (-1800 4850)(-2000 4850);
WIRE 16 -1 (-1800 4950)(-1800 4900);
WIRE 16 -1 (-1800 4900)(-2000 4900);
WIRE 16 -1 (-1800 5000)(-1800 4950);
WIRE 16 -1 (-1800 4950)(-2000 4950);
WIRE 16 -1 (-1800 5050)(-1800 5000);
WIRE 16 -1 (-1800 5000)(-2000 5000);
WIRE 16 -1 (-1800 5100)(-1800 5050);
WIRE 16 -1 (-1800 5050)(-2000 5050);
WIRE 16 -1 (-1800 5150)(-1800 5100);
WIRE 16 -1 (-1800 5100)(-2000 5100);
WIRE 16 -1 (-1800 5200)(-1800 5150);
WIRE 16 -1 (-1800 5150)(-2000 5150);
WIRE 16 -1 (-1800 5250)(-1800 5200);
WIRE 16 -1 (-1800 5200)(-2000 5200);
WIRE 16 -1 (-1800 5300)(-1800 5250);
WIRE 16 -1 (-1800 5250)(-2000 5250);
WIRE 16 -1 (-1800 5350)(-1800 5300);
WIRE 16 -1 (-1800 5300)(-2000 5300);
WIRE 16 -1 (-1800 5400)(-1800 5350);
WIRE 16 -1 (-1800 5350)(-2000 5350);
WIRE 16 -1 (-1800 5400)(-2000 5400);
WIRE 16 -1 (-2950 1400)(-3150 1400);
WIRE 16 -1 (-3150 1450)(-3150 1400);
WIRE 16 -1 (-3150 1400)(-3150 1350);
WIRE 16 -1 (-2950 1350)(-3150 1350);
WIRE 16 -1 (-3150 1350)(-3150 1200);
WIRE 16 -1 (-2950 1450)(-3150 1450);
WIRE 16 -1 (-3150 1500)(-3150 1450);
WIRE 16 -1 (-2950 1500)(-3150 1500);
WIRE 16 -1 (-3150 1550)(-3150 1500);
WIRE 16 -1 (-2950 1550)(-3150 1550);
WIRE 16 -1 (-3150 1600)(-3150 1550);
WIRE 16 -1 (-2950 1600)(-3150 1600);
WIRE 16 -1 (-3150 1650)(-3150 1600);
WIRE 16 -1 (-2950 1650)(-3150 1650);
WIRE 16 -1 (-3150 1700)(-3150 1650);
WIRE 16 -1 (-2950 1700)(-3150 1700);
WIRE 16 -1 (-3150 1750)(-3150 1700);
WIRE 16 -1 (-2950 1750)(-3150 1750);
WIRE 16 -1 (-3150 1800)(-3150 1750);
WIRE 16 -1 (-2950 1800)(-3150 1800);
WIRE 16 -1 (-3150 1850)(-3150 1800);
WIRE 16 -1 (-2950 1850)(-3150 1850);
WIRE 16 -1 (-3150 1900)(-3150 1850);
WIRE 16 -1 (-2950 1900)(-3150 1900);
WIRE 16 -1 (-3150 1950)(-3150 1900);
WIRE 16 -1 (-2950 1950)(-3150 1950);
WIRE 16 -1 (-3150 2000)(-3150 1950);
WIRE 16 -1 (-3150 2050)(-3150 2000);
WIRE 16 -1 (-2950 2000)(-3150 2000);
WIRE 16 -1 (-2950 2050)(-3150 2050);
WIRE 16 -1 (-3150 2100)(-3150 2050);
WIRE 16 -1 (-2950 2100)(-3150 2100);
WIRE 16 -1 (-3150 2150)(-3150 2100);
WIRE 16 -1 (-2950 2150)(-3150 2150);
WIRE 16 -1 (-3150 2200)(-3150 2150);
WIRE 16 -1 (-2950 2200)(-3150 2200);
WIRE 16 -1 (-3150 2250)(-3150 2200);
WIRE 16 -1 (-2950 2250)(-3150 2250);
WIRE 16 -1 (-3150 2300)(-3150 2250);
WIRE 16 -1 (-2950 2300)(-3150 2300);
WIRE 16 -1 (-3150 2350)(-3150 2300);
WIRE 16 -1 (-2950 2350)(-3150 2350);
WIRE 16 -1 (-3150 2400)(-3150 2350);
WIRE 16 -1 (-2950 2400)(-3150 2400);
WIRE 16 -1 (-3150 2450)(-3150 2400);
WIRE 16 -1 (-2950 2450)(-3150 2450);
WIRE 16 -1 (-3150 2500)(-3150 2450);
WIRE 16 -1 (-2950 2500)(-3150 2500);
WIRE 16 -1 (-3150 2550)(-3150 2500);
WIRE 16 -1 (-2950 2550)(-3150 2550);
WIRE 16 -1 (-3150 2600)(-3150 2550);
WIRE 16 -1 (-2950 2600)(-3150 2600);
WIRE 16 -1 (-3150 2650)(-3150 2600);
WIRE 16 -1 (-2950 2650)(-3150 2650);
WIRE 16 -1 (-3150 2700)(-3150 2650);
WIRE 16 -1 (-2950 2700)(-3150 2700);
WIRE 16 -1 (-3150 2750)(-3150 2700);
WIRE 16 -1 (-2950 2750)(-3150 2750);
WIRE 16 -1 (-3150 2800)(-3150 2750);
WIRE 16 -1 (-2950 2800)(-3150 2800);
WIRE 16 -1 (-3150 2850)(-3150 2800);
WIRE 16 -1 (-2950 2850)(-3150 2850);
WIRE 16 -1 (-3150 2900)(-3150 2850);
WIRE 16 -1 (-2950 2900)(-3150 2900);
WIRE 16 -1 (-3150 2950)(-3150 2900);
WIRE 16 -1 (-2950 2950)(-3150 2950);
WIRE 16 -1 (-3150 3000)(-3150 2950);
WIRE 16 -1 (-2950 3000)(-3150 3000);
WIRE 16 -1 (-3150 3050)(-3150 3000);
WIRE 16 -1 (-2950 3050)(-3150 3050);
WIRE 16 -1 (-3150 3100)(-3150 3050);
WIRE 16 -1 (-2950 3100)(-3150 3100);
WIRE 16 -1 (-3150 3150)(-3150 3100);
WIRE 16 -1 (-2950 3150)(-3150 3150);
WIRE 16 -1 (-3150 3200)(-3150 3150);
WIRE 16 -1 (-2950 3200)(-3150 3200);
WIRE 16 -1 (-3150 3250)(-3150 3200);
WIRE 16 -1 (-2950 3250)(-3150 3250);
WIRE 16 -1 (-3150 3300)(-3150 3250);
WIRE 16 -1 (-2950 3300)(-3150 3300);
WIRE 16 -1 (-3150 3350)(-3150 3300);
WIRE 16 -1 (-2950 3350)(-3150 3350);
WIRE 16 -1 (-3150 3400)(-3150 3350);
WIRE 16 -1 (-2950 3400)(-3150 3400);
WIRE 16 -1 (-3150 3450)(-3150 3400);
WIRE 16 -1 (-2950 3450)(-3150 3450);
WIRE 16 -1 (-3150 3500)(-3150 3450);
WIRE 16 -1 (-2950 3500)(-3150 3500);
WIRE 16 -1 (-3150 3550)(-3150 3500);
WIRE 16 -1 (-2950 3550)(-3150 3550);
WIRE 16 -1 (-3150 3600)(-3150 3550);
WIRE 16 -1 (-2950 3600)(-3150 3600);
WIRE 16 -1 (-3150 3650)(-3150 3600);
WIRE 16 -1 (-2950 3650)(-3150 3650);
WIRE 16 -1 (-3150 3700)(-3150 3650);
WIRE 16 -1 (-2950 3700)(-3150 3700);
WIRE 16 -1 (-3150 3750)(-3150 3700);
WIRE 16 -1 (-2950 3750)(-3150 3750);
WIRE 16 -1 (-3150 3800)(-3150 3750);
WIRE 16 -1 (-2950 3800)(-3150 3800);
WIRE 16 -1 (-3150 3850)(-3150 3800);
WIRE 16 -1 (-2950 3850)(-3150 3850);
WIRE 16 -1 (-3150 3900)(-3150 3850);
WIRE 16 -1 (-2950 3900)(-3150 3900);
WIRE 16 -1 (-3150 3950)(-3150 3900);
WIRE 16 -1 (-2950 3950)(-3150 3950);
WIRE 16 -1 (-3150 4000)(-3150 3950);
WIRE 16 -1 (-2950 4000)(-3150 4000);
WIRE 16 -1 (-3150 4050)(-3150 4000);
WIRE 16 -1 (-3150 4100)(-3150 4050);
WIRE 16 -1 (-2950 4050)(-3150 4050);
WIRE 16 -1 (-2950 4100)(-3150 4100);
WIRE 16 -1 (-3150 4150)(-3150 4100);
WIRE 16 -1 (-2950 4150)(-3150 4150);
WIRE 16 -1 (-3150 4200)(-3150 4150);
WIRE 16 -1 (-2950 4200)(-3150 4200);
WIRE 16 -1 (-3150 4250)(-3150 4200);
WIRE 16 -1 (-2950 4250)(-3150 4250);
WIRE 16 -1 (-3150 4300)(-3150 4250);
WIRE 16 -1 (-2950 4300)(-3150 4300);
WIRE 16 -1 (-3150 4350)(-3150 4300);
WIRE 16 -1 (-2950 4350)(-3150 4350);
WIRE 16 -1 (-3150 4400)(-3150 4350);
WIRE 16 -1 (-2950 4400)(-3150 4400);
WIRE 16 -1 (-3150 4450)(-3150 4400);
WIRE 16 -1 (-2950 4450)(-3150 4450);
WIRE 16 -1 (-3150 4500)(-3150 4450);
WIRE 16 -1 (-2950 4500)(-3150 4500);
WIRE 16 -1 (-3150 4550)(-3150 4500);
WIRE 16 -1 (-2950 4550)(-3150 4550);
WIRE 16 -1 (-3150 4600)(-3150 4550);
WIRE 16 -1 (-2950 4600)(-3150 4600);
WIRE 16 -1 (-3150 4650)(-3150 4600);
WIRE 16 -1 (-2950 4650)(-3150 4650);
WIRE 16 -1 (-3150 4700)(-3150 4650);
WIRE 16 -1 (-2950 4700)(-3150 4700);
WIRE 16 -1 (-3150 4750)(-3150 4700);
WIRE 16 -1 (-2950 4750)(-3150 4750);
WIRE 16 -1 (-3150 4800)(-3150 4750);
WIRE 16 -1 (-2950 4800)(-3150 4800);
WIRE 16 -1 (-3150 4850)(-3150 4800);
WIRE 16 -1 (-2950 4850)(-3150 4850);
WIRE 16 -1 (-3150 4900)(-3150 4850);
WIRE 16 -1 (-2950 4900)(-3150 4900);
WIRE 16 -1 (-3150 4950)(-3150 4900);
WIRE 16 -1 (-2950 4950)(-3150 4950);
WIRE 16 -1 (-3150 5000)(-3150 4950);
WIRE 16 -1 (-2950 5000)(-3150 5000);
WIRE 16 -1 (-3150 5050)(-3150 5000);
WIRE 16 -1 (-2950 5050)(-3150 5050);
WIRE 16 -1 (-3150 5100)(-3150 5050);
WIRE 16 -1 (-2950 5100)(-3150 5100);
WIRE 16 -1 (-3150 5150)(-3150 5100);
WIRE 16 -1 (-2950 5150)(-3150 5150);
WIRE 16 -1 (-3150 5200)(-3150 5150);
WIRE 16 -1 (-2950 5200)(-3150 5200);
WIRE 16 -1 (-3150 5250)(-3150 5200);
WIRE 16 -1 (-2950 5250)(-3150 5250);
WIRE 16 -1 (-3150 5300)(-3150 5250);
WIRE 16 -1 (-2950 5300)(-3150 5300);
WIRE 16 -1 (-3150 5350)(-3150 5300);
WIRE 16 -1 (-2950 5350)(-3150 5350);
WIRE 16 -1 (-3150 5400)(-3150 5350);
WIRE 16 -1 (-2950 5400)(-3150 5400);
WIRE 16 -1 (-1475 1850)(-1475 1800);
WIRE 16 -1 (-1475 1850)(-2000 1850);
FORCEPROP 2 LAST SIG_NAME NCF_CPU0_P2_GND
J 0
(-1885 1860);
DISPLAY 0.553191 (-1885 1860);
PAINT SKYBLUE (-1885 1860);
FORCEPROP 2 LASTPROP $XRERR UNIQUE?
J 0
(-2125 1860);
DISPLAY 0.638298 (-2125 1860);
PAINT MONO (-2125 1860);
DISPLAY INVISIBLE (-2125 1860);
WIRE 16 -1 (-1475 1800)(-1475 1750);
WIRE 16 -1 (-1475 1800)(-2000 1800);
WIRE 16 -1 (-1475 1750)(-1475 1700);
WIRE 16 -1 (-1475 1750)(-2000 1750);
WIRE 16 -1 (-1475 1700)(-1475 1650);
WIRE 16 -1 (-1475 1700)(-2000 1700);
WIRE 16 -1 (-1475 1650)(-1475 1600);
WIRE 16 -1 (-1475 1650)(-2000 1650);
WIRE 16 -1 (-1475 1600)(-1475 1550);
WIRE 16 -1 (-1475 1600)(-2000 1600);
WIRE 16 -1 (-1475 1550)(-1475 1500);
WIRE 16 -1 (-1475 1550)(-2000 1550);
WIRE 16 -1 (-1475 1500)(-1475 1450);
WIRE 16 -1 (-1475 1500)(-2000 1500);
WIRE 16 -1 (-1475 1450)(-1475 1400);
WIRE 16 -1 (-1475 1450)(-2000 1450);
WIRE 16 -1 (-1475 1400)(-1475 1350);
WIRE 16 -1 (-1475 1400)(-2000 1400);
WIRE 16 -1 (-1475 1350)(-1475 1175);
WIRE 16 -1 (-1475 1350)(-2000 1350);
WIRE 16 -1 (-2000 1900)(-1325 1900);
FORCEPROP 2 LAST SIG_NAME NCF_A1_CPU0_P2_GND
J 0
(-1835 1910);
DISPLAY 0.553191 (-1835 1910);
PAINT SKYBLUE (-1835 1910);
FORCEPROP 2 LASTPROP $XRERR UNIQUE?
J 0
(-2075 1910);
DISPLAY 0.638298 (-2075 1910);
PAINT MONO (-2075 1910);
DISPLAY INVISIBLE (-2075 1910);
WIRE 16 -1 (-1325 1900)(-1325 1725);
DOT 1 (-7675 3475);
DOT 1 (-5725 4225);
DOT 1 (-7550 4425);
DOT 1 (-5725 4275);
DOT 1 (-1800 4250);
DOT 1 (-1800 2600);
DOT 1 (-1800 2550);
DOT 1 (-1800 2150);
DOT 1 (-1800 2400);
DOT 1 (-1475 1800);
DOT 1 (-1475 1600);
DOT 1 (-1475 1500);
DOT 1 (-5750 4375);
DOT 1 (-5750 4475);
DOT 1 (-5650 3375);
DOT 1 (-5725 3675);
DOT 1 (-5725 3725);
DOT 1 (-5725 3775);
DOT 1 (-5725 3825);
DOT 1 (-5725 3875);
DOT 1 (-5650 3475);
DOT 1 (-5650 3425);
DOT 1 (-5725 3925);
DOT 1 (-7550 4475);
DOT 1 (-7550 4525);
DOT 1 (-7550 4575);
DOT 1 (-5725 3975);
DOT 1 (-5725 4025);
DOT 1 (-5725 4075);
DOT 1 (-5725 4175);
DOT 1 (-5750 4425);
DOT 1 (-5750 4525);
DOT 1 (-5750 4575);
DOT 1 (-4700 4575);
DOT 1 (-3150 1350);
DOT 1 (-3150 1400);
DOT 1 (-3150 1450);
DOT 1 (-3150 1500);
DOT 1 (-3150 1550);
DOT 1 (-3150 1600);
DOT 1 (-3150 1650);
DOT 1 (-3150 1700);
DOT 1 (-3150 1750);
DOT 1 (-3150 1800);
DOT 1 (-3150 1850);
DOT 1 (-3150 1900);
DOT 1 (-3150 1950);
DOT 1 (-3150 2000);
DOT 1 (-3150 2050);
DOT 1 (-3150 2100);
DOT 1 (-3150 2150);
DOT 1 (-3150 2200);
DOT 1 (-3150 2250);
DOT 1 (-3150 2350);
DOT 1 (-3150 2300);
DOT 1 (-3150 2400);
DOT 1 (-3150 2450);
DOT 1 (-3150 2500);
DOT 1 (-3150 2550);
DOT 1 (-3150 2600);
DOT 1 (-3150 2650);
DOT 1 (-3150 2700);
DOT 1 (-3150 2750);
DOT 1 (-3150 2850);
DOT 1 (-3150 2800);
DOT 1 (-3150 2900);
DOT 1 (-3150 2950);
DOT 1 (-3150 3000);
DOT 1 (-3150 3050);
DOT 1 (-3150 3100);
DOT 1 (-3150 3150);
DOT 1 (-3150 3200);
DOT 1 (-3150 3250);
DOT 1 (-3150 3300);
DOT 1 (-3150 3350);
DOT 1 (-3150 3400);
DOT 1 (-3150 3500);
DOT 1 (-3150 3450);
DOT 1 (-3150 3550);
DOT 1 (-3150 3600);
DOT 1 (-3150 3650);
DOT 1 (-3150 3700);
DOT 1 (-3150 3750);
DOT 1 (-3150 3800);
DOT 1 (-3150 3850);
DOT 1 (-3150 3900);
DOT 1 (-1475 1350);
DOT 1 (-1475 1400);
DOT 1 (-1475 1450);
DOT 1 (-1475 1550);
DOT 1 (-1475 1700);
DOT 1 (-1475 1650);
DOT 1 (-1475 1750);
DOT 1 (-1800 2000);
DOT 1 (-1800 2050);
DOT 1 (-1800 2100);
DOT 1 (-1800 2200);
DOT 1 (-1800 2250);
DOT 1 (-1800 2350);
DOT 1 (-1800 2300);
DOT 1 (-1800 2450);
DOT 1 (-1800 2500);
DOT 1 (-1800 2650);
DOT 1 (-1800 2700);
DOT 1 (-1800 2750);
DOT 1 (-1800 2850);
DOT 1 (-1800 2800);
DOT 1 (-1800 2900);
DOT 1 (-1800 2950);
DOT 1 (-1800 3000);
DOT 1 (-1800 3050);
DOT 1 (-1800 3100);
DOT 1 (-1800 3150);
DOT 1 (-1800 3200);
DOT 1 (-1800 3250);
DOT 1 (-1800 3300);
DOT 1 (-1800 3350);
DOT 1 (-1800 3400);
DOT 1 (-1800 3450);
DOT 1 (-1800 3500);
DOT 1 (-1800 3550);
DOT 1 (-1800 3600);
DOT 1 (-1800 3650);
DOT 1 (-1800 3700);
DOT 1 (-1800 3750);
DOT 1 (-1800 3800);
DOT 1 (-1800 3850);
DOT 1 (-1800 3900);
DOT 1 (-3150 3950);
DOT 1 (-3150 4000);
DOT 1 (-3150 4050);
DOT 1 (-3150 4100);
DOT 1 (-3150 4150);
DOT 1 (-3150 4200);
DOT 1 (-3150 4250);
DOT 1 (-3150 4300);
DOT 1 (-3150 4400);
DOT 1 (-3150 4350);
DOT 1 (-3150 4450);
DOT 1 (-3150 4500);
DOT 1 (-3150 4550);
DOT 1 (-3150 4650);
DOT 1 (-3150 4600);
DOT 1 (-3150 4700);
DOT 1 (-3150 4750);
DOT 1 (-3150 4800);
DOT 1 (-3150 4900);
DOT 1 (-3150 4850);
DOT 1 (-3150 4950);
DOT 1 (-3150 5000);
DOT 1 (-3150 5050);
DOT 1 (-3150 5100);
DOT 1 (-3150 5150);
DOT 1 (-3150 5200);
DOT 1 (-3150 5250);
DOT 1 (-3150 5300);
DOT 1 (-3150 5350);
DOT 1 (-1800 3950);
DOT 1 (-1800 4000);
DOT 1 (-1800 4050);
DOT 1 (-1800 4100);
DOT 1 (-1800 4150);
DOT 1 (-1800 4200);
DOT 1 (-1800 4300);
DOT 1 (-1800 4350);
DOT 1 (-1800 4400);
DOT 1 (-1800 4450);
DOT 1 (-1800 4500);
DOT 1 (-1800 4550);
DOT 1 (-1800 4600);
DOT 1 (-1800 4650);
DOT 1 (-1800 4700);
DOT 1 (-1800 4750);
DOT 1 (-1800 4800);
DOT 1 (-1800 4850);
DOT 1 (-1800 4900);
DOT 1 (-1800 4950);
DOT 1 (-1800 5000);
DOT 1 (-1800 5050);
DOT 1 (-1800 5100);
DOT 1 (-1800 5150);
DOT 1 (-1800 5200);
DOT 1 (-1800 5250);
DOT 1 (-1800 5300);
DOT 1 (-1800 5350);
QUIT
